(kicad_pcb
	(version 20260206)
	(generator "pcbnew")
	(generator_version "10.0")
	(general
		(thickness 1.6)
		(legacy_teardrops no)
	)
	(paper "A4")
	(title_block
		(title "03242023_DA0F0TMBIJ0_F0T_Motherboard_J_brd_V01_OCP.brd")
		(comment 1 "Grand Teton / footprints 1615-1621 of 6105")
	)
	(layers
		(0 "F.Cu" signal "TOP")
		(4 "In1.Cu" signal "GND")
		(6 "In2.Cu" signal "IN1")
		(8 "In3.Cu" signal "GND1")
		(10 "In4.Cu" signal "IN2")
		(12 "In5.Cu" signal "GND2")
		(14 "In6.Cu" signal "IN3")
		(16 "In7.Cu" signal "GND3")
		(18 "In8.Cu" signal "VCC")
		(20 "In9.Cu" signal "VCC1")
		(22 "In10.Cu" signal "GND4")
		(24 "In11.Cu" signal "IN4")
		(26 "In12.Cu" signal "GND5")
		(28 "In13.Cu" signal "IN5")
		(30 "In14.Cu" signal "GND6")
		(32 "In15.Cu" signal "IN6")
		(34 "In16.Cu" signal "GND7")
		(2 "B.Cu" signal "BOTTOM")
		(9 "F.Adhes" user "F.Adhesive")
		(11 "B.Adhes" user "B.Adhesive")
		(13 "F.Paste" user "Package Geometry/Pastemask Top")
		(15 "B.Paste" user "Package Geometry/Pastemask Bottom")
		(5 "F.SilkS" user "Ref Des/Silkscreen Top")
		(7 "B.SilkS" user "Ref Des/Silkscreen Bottom")
		(1 "F.Mask" user "Board Geometry/Soldermask Top")
		(3 "B.Mask" user "Board Geometry/Soldermask Bottom")
		(17 "Dwgs.User" user "User.Drawings")
		(19 "Cmts.User" user "User.Comments")
		(21 "Eco1.User" user "User.Eco1")
		(23 "Eco2.User" user "User.Eco2")
		(25 "Edge.Cuts" user "Board Geometry/Outline")
		(27 "Margin" user)
		(31 "F.CrtYd" user "Package Geometry/Place Bound Top")
		(29 "B.CrtYd" user "Package Geometry/Place Bound Bottom")
		(35 "F.Fab" user "Ref Des/Assembly Top")
		(33 "B.Fab" user "Ref Des/Assembly Bottom")
	)
	(footprint ""
		(layer "F.Cu")
		(at 307.456078 -422.87317 90)
		(property "Reference" "U308"
			(at -2.590292 -0.651256 0)
			(unlocked yes)
			(layer "F.SilkS")
			(effects
				(font
					(size 0.7874 0.5842)
					(thickness 0.1524)
				)
				(justify left)
			)
		)
		(property "Value" ""
			(at 0 0 90)
			(layer "F.Fab")
			(effects
				(font
					(size 1.27 1.27)
				)
			)
		)
		(duplicate_pad_numbers_are_jumpers no)
		(fp_line
			(start 1.38176 -1.100074)
			(end 0.592074 -1.100074)
			(stroke
				(width 0.1524)
				(type default)
			)
			(layer "F.SilkS")
		)
		(fp_line
			(start 0.592074 -1.100074)
			(end 0 -0.508)
			(stroke
				(width 0.1524)
				(type default)
			)
			(layer "F.SilkS")
		)
		(fp_line
			(start -0.592074 -1.100074)
			(end -1.38176 -1.100074)
			(stroke
				(width 0.1524)
				(type default)
			)
			(layer "F.SilkS")
		)
		(fp_line
			(start -1.38176 -1.100074)
			(end -1.38176 1.100074)
			(stroke
				(width 0.1524)
				(type default)
			)
			(layer "F.SilkS")
		)
		(fp_line
			(start 0 -0.508)
			(end -0.592074 -1.100074)
			(stroke
				(width 0.1524)
				(type default)
			)
			(layer "F.SilkS")
		)
		(fp_line
			(start 1.38176 1.100074)
			(end 1.38176 -1.100074)
			(stroke
				(width 0.1524)
				(type default)
			)
			(layer "F.SilkS")
		)
		(fp_line
			(start -1.38176 1.100074)
			(end 1.38176 1.100074)
			(stroke
				(width 0.1524)
				(type default)
			)
			(layer "F.SilkS")
		)
		(fp_poly
			(pts
				(xy -1.50241 -0.649986) (xy -1.9431 -0.429768) (xy -1.9431 -0.870204)
			)
			(stroke
				(width 0)
				(type default)
			)
			(fill yes)
			(layer "F.SilkS")
		)
		(fp_line
			(start 0.674878 -1.100074)
			(end -0.674878 -1.100074)
			(stroke
				(width 0.1)
				(type default)
			)
			(layer "F.Fab")
		)
		(fp_line
			(start -0.674878 -1.100074)
			(end -0.674878 1.100074)
			(stroke
				(width 0.1)
				(type default)
			)
			(layer "F.Fab")
		)
		(fp_line
			(start 0.674878 1.100074)
			(end 0.674878 -1.100074)
			(stroke
				(width 0.1)
				(type default)
			)
			(layer "F.Fab")
		)
		(fp_line
			(start -0.674878 1.100074)
			(end 0.674878 1.100074)
			(stroke
				(width 0.1)
				(type default)
			)
			(layer "F.Fab")
		)
		(fp_poly
			(pts
				(xy -1.9431 -0.870204) (xy -1.50241 -0.649986) (xy -1.9431 -0.429768)
			)
			(stroke
				(width 0)
				(type default)
			)
			(fill yes)
			(layer "F.Fab")
		)
		(pad "1" smd rect
			(at -0.94996 -0.649986)
			(size 0.4318 0.6096)
			(layers "F.Cu" "F.Mask" "F.Paste")
			(net "PWRGD_P3V3_AUX_PDB_R")
		)
		(pad "2" smd rect
			(at -0.94996 0)
			(size 0.4318 0.6096)
			(layers "F.Cu" "F.Mask" "F.Paste")
			(net "GND")
		)
		(pad "3" smd rect
			(at -0.94996 0.649986)
			(size 0.4318 0.6096)
			(layers "F.Cu" "F.Mask" "F.Paste")
			(net "Net_8600")
		)
		(pad "4" smd rect
			(at 0.94996 0.649986)
			(size 0.4318 0.6096)
			(layers "F.Cu" "F.Mask" "F.Paste")
			(net "Net_8599")
		)
		(pad "5" smd rect
			(at 0.94996 0)
			(size 0.4318 0.6096)
			(layers "F.Cu" "F.Mask" "F.Paste")
			(net "P3V3_AUX")
		)
		(pad "6" smd rect
			(at 0.94996 -0.649986)
			(size 0.4318 0.6096)
			(layers "F.Cu" "F.Mask" "F.Paste")
			(net "PWRGD_P3V3_AUX_PDB_BUF_R")
		)
	)
	(footprint ""
		(layer "F.Cu")
		(at 293.549832 -435.600094)
		(property "Reference" "H91"
			(at -6.814312 -3.983736 0)
			(unlocked yes)
			(layer "F.SilkS")
			(effects
				(font
					(size 0.7874 0.5842)
					(thickness 0.1524)
				)
				(justify left)
			)
		)
		(property "Value" ""
			(at 0 0 0)
			(layer "F.Fab")
			(effects
				(font
					(size 1.27 1.27)
				)
			)
		)
		(duplicate_pad_numbers_are_jumpers no)
		(pad "1" thru_hole circle
			(at 0 0)
			(size 10.0076 10.0076)
			(drill 5.6134)
			(layers "*.Cu" "*.Mask")
			(remove_unused_layers no)
			(net "GND")
			(clearance -1.9431)
		)
	)
	(footprint ""
		(layer "F.Cu")
		(at 36.956238 -133.81482 180)
		(property "Reference" "R2570"
			(at 0 0 180)
			(layer "F.SilkS")
			(hide yes)
			(effects
				(font
					(size 1.27 1.27)
				)
			)
		)
		(property "Value" ""
			(at 0 0 180)
			(layer "F.Fab")
			(effects
				(font
					(size 1.27 1.27)
				)
			)
		)
		(duplicate_pad_numbers_are_jumpers no)
		(fp_line
			(start 0.7874 0.4064)
			(end -0.7874 0.4064)
			(stroke
				(width 0.1524)
				(type default)
			)
			(layer "F.SilkS")
		)
		(fp_line
			(start 0.7874 -0.4064)
			(end 0.7874 0.4064)
			(stroke
				(width 0.1524)
				(type default)
			)
			(layer "F.SilkS")
		)
		(fp_line
			(start -0.7874 0.4064)
			(end -0.7874 -0.4064)
			(stroke
				(width 0.1524)
				(type default)
			)
			(layer "F.SilkS")
		)
		(fp_line
			(start -0.7874 -0.4064)
			(end 0.7874 -0.4064)
			(stroke
				(width 0.1524)
				(type default)
			)
			(layer "F.SilkS")
		)
		(fp_line
			(start 0.67945 0.3048)
			(end 0.120396 0.3048)
			(stroke
				(width 0.1)
				(type default)
			)
			(layer "F.Fab")
		)
		(fp_line
			(start 0.67945 -0.3048)
			(end 0.67945 0.3048)
			(stroke
				(width 0.1)
				(type default)
			)
			(layer "F.Fab")
		)
		(fp_line
			(start 0.12065 -0.2794)
			(end 0.12065 -0.3048)
			(stroke
				(width 0.1)
				(type default)
			)
			(layer "F.Fab")
		)
		(fp_line
			(start 0.12065 -0.3048)
			(end 0.67945 -0.3048)
			(stroke
				(width 0.1)
				(type default)
			)
			(layer "F.Fab")
		)
		(fp_line
			(start 0.120396 0.3048)
			(end 0.120396 0.2794)
			(stroke
				(width 0.1)
				(type default)
			)
			(layer "F.Fab")
		)
		(fp_line
			(start 0.120396 0.2794)
			(end -0.12065 0.2794)
			(stroke
				(width 0.1)
				(type default)
			)
			(layer "F.Fab")
		)
		(fp_line
			(start -0.12065 0.3048)
			(end -0.67945 0.3048)
			(stroke
				(width 0.1)
				(type default)
			)
			(layer "F.Fab")
		)
		(fp_line
			(start -0.12065 0.2794)
			(end -0.12065 0.3048)
			(stroke
				(width 0.1)
				(type default)
			)
			(layer "F.Fab")
		)
		(fp_line
			(start -0.12065 -0.2794)
			(end 0.12065 -0.2794)
			(stroke
				(width 0.1)
				(type default)
			)
			(layer "F.Fab")
		)
		(fp_line
			(start -0.12065 -0.305054)
			(end -0.12065 -0.2794)
			(stroke
				(width 0.1)
				(type default)
			)
			(layer "F.Fab")
		)
		(fp_line
			(start -0.67945 0.3048)
			(end -0.67945 -0.305054)
			(stroke
				(width 0.1)
				(type default)
			)
			(layer "F.Fab")
		)
		(fp_line
			(start -0.67945 -0.305054)
			(end -0.12065 -0.305054)
			(stroke
				(width 0.1)
				(type default)
			)
			(layer "F.Fab")
		)
		(pad "1" smd circle
			(at -0.40005 0 180)
			(size 0 0)
			(layers "F.Cu" "F.Mask" "F.Paste")
			(net "FM_PVCCFA_EHV_CPU1_EN")
		)
		(pad "2" smd circle
			(at 0.40005 0 180)
			(size 0 0)
			(layers "F.Cu" "F.Mask" "F.Paste")
			(net "PVCCFA_EHV_CPU1_EN_R")
		)
	)
	(footprint ""
		(layer "F.Cu")
		(at 106.476038 -38.983158)
		(property "Reference" "R3189"
			(at 0 0 0)
			(layer "F.SilkS")
			(hide yes)
			(effects
				(font
					(size 1.27 1.27)
				)
			)
		)
		(property "Value" ""
			(at 0 0 0)
			(layer "F.Fab")
			(effects
				(font
					(size 1.27 1.27)
				)
			)
		)
		(duplicate_pad_numbers_are_jumpers no)
		(fp_line
			(start -0.7874 -0.4064)
			(end 0.7874 -0.4064)
			(stroke
				(width 0.1524)
				(type default)
			)
			(layer "F.SilkS")
		)
		(fp_line
			(start -0.7874 0.4064)
			(end -0.7874 -0.4064)
			(stroke
				(width 0.1524)
				(type default)
			)
			(layer "F.SilkS")
		)
		(fp_line
			(start 0.7874 -0.4064)
			(end 0.7874 0.4064)
			(stroke
				(width 0.1524)
				(type default)
			)
			(layer "F.SilkS")
		)
		(fp_line
			(start 0.7874 0.4064)
			(end -0.7874 0.4064)
			(stroke
				(width 0.1524)
				(type default)
			)
			(layer "F.SilkS")
		)
		(fp_line
			(start -0.67945 -0.305054)
			(end -0.12065 -0.305054)
			(stroke
				(width 0.1)
				(type default)
			)
			(layer "F.Fab")
		)
		(fp_line
			(start -0.67945 0.3048)
			(end -0.67945 -0.305054)
			(stroke
				(width 0.1)
				(type default)
			)
			(layer "F.Fab")
		)
		(fp_line
			(start -0.12065 -0.305054)
			(end -0.12065 -0.2794)
			(stroke
				(width 0.1)
				(type default)
			)
			(layer "F.Fab")
		)
		(fp_line
			(start -0.12065 -0.2794)
			(end 0.12065 -0.2794)
			(stroke
				(width 0.1)
				(type default)
			)
			(layer "F.Fab")
		)
		(fp_line
			(start -0.12065 0.2794)
			(end -0.12065 0.3048)
			(stroke
				(width 0.1)
				(type default)
			)
			(layer "F.Fab")
		)
		(fp_line
			(start -0.12065 0.3048)
			(end -0.67945 0.3048)
			(stroke
				(width 0.1)
				(type default)
			)
			(layer "F.Fab")
		)
		(fp_line
			(start 0.120396 0.2794)
			(end -0.12065 0.2794)
			(stroke
				(width 0.1)
				(type default)
			)
			(layer "F.Fab")
		)
		(fp_line
			(start 0.120396 0.3048)
			(end 0.120396 0.2794)
			(stroke
				(width 0.1)
				(type default)
			)
			(layer "F.Fab")
		)
		(fp_line
			(start 0.12065 -0.3048)
			(end 0.67945 -0.3048)
			(stroke
				(width 0.1)
				(type default)
			)
			(layer "F.Fab")
		)
		(fp_line
			(start 0.12065 -0.2794)
			(end 0.12065 -0.3048)
			(stroke
				(width 0.1)
				(type default)
			)
			(layer "F.Fab")
		)
		(fp_line
			(start 0.67945 -0.3048)
			(end 0.67945 0.3048)
			(stroke
				(width 0.1)
				(type default)
			)
			(layer "F.Fab")
		)
		(fp_line
			(start 0.67945 0.3048)
			(end 0.120396 0.3048)
			(stroke
				(width 0.1)
				(type default)
			)
			(layer "F.Fab")
		)
		(pad "1" smd circle
			(at -0.40005 0)
			(size 0 0)
			(layers "F.Cu" "F.Mask" "F.Paste")
			(net "RST_OCP_V3_2_BUF_N")
		)
		(pad "2" smd circle
			(at 0.40005 0)
			(size 0 0)
			(layers "F.Cu" "F.Mask" "F.Paste")
			(net "RST_PERST3_OCP_V3_2_N")
		)
	)
	(footprint ""
		(layer "F.Cu")
		(at 453.043544 -25.638506 180)
		(property "Reference" "PR4524"
			(at 0 0 180)
			(layer "F.SilkS")
			(hide yes)
			(effects
				(font
					(size 1.27 1.27)
				)
			)
		)
		(property "Value" ""
			(at 0 0 180)
			(layer "F.Fab")
			(effects
				(font
					(size 1.27 1.27)
				)
			)
		)
		(duplicate_pad_numbers_are_jumpers no)
		(fp_line
			(start 0.7874 0.4064)
			(end -0.7874 0.4064)
			(stroke
				(width 0.1524)
				(type default)
			)
			(layer "F.SilkS")
		)
		(fp_line
			(start 0.7874 -0.4064)
			(end 0.7874 0.4064)
			(stroke
				(width 0.1524)
				(type default)
			)
			(layer "F.SilkS")
		)
		(fp_line
			(start -0.7874 0.4064)
			(end -0.7874 -0.4064)
			(stroke
				(width 0.1524)
				(type default)
			)
			(layer "F.SilkS")
		)
		(fp_line
			(start -0.7874 -0.4064)
			(end 0.7874 -0.4064)
			(stroke
				(width 0.1524)
				(type default)
			)
			(layer "F.SilkS")
		)
		(fp_line
			(start 0.67945 0.3048)
			(end 0.120396 0.3048)
			(stroke
				(width 0.1)
				(type default)
			)
			(layer "F.Fab")
		)
		(fp_line
			(start 0.67945 -0.3048)
			(end 0.67945 0.3048)
			(stroke
				(width 0.1)
				(type default)
			)
			(layer "F.Fab")
		)
		(fp_line
			(start 0.12065 -0.2794)
			(end 0.12065 -0.3048)
			(stroke
				(width 0.1)
				(type default)
			)
			(layer "F.Fab")
		)
		(fp_line
			(start 0.12065 -0.3048)
			(end 0.67945 -0.3048)
			(stroke
				(width 0.1)
				(type default)
			)
			(layer "F.Fab")
		)
		(fp_line
			(start 0.120396 0.3048)
			(end 0.120396 0.2794)
			(stroke
				(width 0.1)
				(type default)
			)
			(layer "F.Fab")
		)
		(fp_line
			(start 0.120396 0.2794)
			(end -0.12065 0.2794)
			(stroke
				(width 0.1)
				(type default)
			)
			(layer "F.Fab")
		)
		(fp_line
			(start -0.12065 0.3048)
			(end -0.67945 0.3048)
			(stroke
				(width 0.1)
				(type default)
			)
			(layer "F.Fab")
		)
		(fp_line
			(start -0.12065 0.2794)
			(end -0.12065 0.3048)
			(stroke
				(width 0.1)
				(type default)
			)
			(layer "F.Fab")
		)
		(fp_line
			(start -0.12065 -0.2794)
			(end 0.12065 -0.2794)
			(stroke
				(width 0.1)
				(type default)
			)
			(layer "F.Fab")
		)
		(fp_line
			(start -0.12065 -0.305054)
			(end -0.12065 -0.2794)
			(stroke
				(width 0.1)
				(type default)
			)
			(layer "F.Fab")
		)
		(fp_line
			(start -0.67945 0.3048)
			(end -0.67945 -0.305054)
			(stroke
				(width 0.1)
				(type default)
			)
			(layer "F.Fab")
		)
		(fp_line
			(start -0.67945 -0.305054)
			(end -0.12065 -0.305054)
			(stroke
				(width 0.1)
				(type default)
			)
			(layer "F.Fab")
		)
		(pad "1" smd circle
			(at -0.40005 0 180)
			(size 0 0)
			(layers "F.Cu" "F.Mask" "F.Paste")
			(net "P12V_OCP_SFF")
		)
		(pad "2" smd circle
			(at 0.40005 0 180)
			(size 0 0)
			(layers "F.Cu" "F.Mask" "F.Paste")
			(net "P12V_OCP_GATE_1")
		)
	)
	(footprint ""
		(layer "F.Cu")
		(at 362.646468 -358.93375)
		(property "Reference" "PC100"
			(at 0 0 0)
			(layer "F.SilkS")
			(hide yes)
			(effects
				(font
					(size 1.27 1.27)
				)
			)
		)
		(property "Value" ""
			(at 0 0 0)
			(layer "F.Fab")
			(effects
				(font
					(size 1.27 1.27)
				)
			)
		)
		(duplicate_pad_numbers_are_jumpers no)
		(fp_line
			(start -0.7874 -0.4064)
			(end 0.7874 -0.4064)
			(stroke
				(width 0.1524)
				(type default)
			)
			(layer "F.SilkS")
		)
		(fp_line
			(start -0.7874 0.4064)
			(end -0.7874 -0.4064)
			(stroke
				(width 0.1524)
				(type default)
			)
			(layer "F.SilkS")
		)
		(fp_line
			(start 0.7874 -0.4064)
			(end 0.7874 0.4064)
			(stroke
				(width 0.1524)
				(type default)
			)
			(layer "F.SilkS")
		)
		(fp_line
			(start 0.7874 0.4064)
			(end -0.7874 0.4064)
			(stroke
				(width 0.1524)
				(type default)
			)
			(layer "F.SilkS")
		)
		(fp_line
			(start -0.67945 -0.305054)
			(end -0.12065 -0.305054)
			(stroke
				(width 0.1)
				(type default)
			)
			(layer "F.Fab")
		)
		(fp_line
			(start -0.67945 0.3048)
			(end -0.67945 -0.305054)
			(stroke
				(width 0.1)
				(type default)
			)
			(layer "F.Fab")
		)
		(fp_line
			(start -0.12065 -0.305054)
			(end -0.12065 -0.2794)
			(stroke
				(width 0.1)
				(type default)
			)
			(layer "F.Fab")
		)
		(fp_line
			(start -0.12065 -0.2794)
			(end 0.12065 -0.2794)
			(stroke
				(width 0.1)
				(type default)
			)
			(layer "F.Fab")
		)
		(fp_line
			(start -0.12065 0.2794)
			(end -0.12065 0.3048)
			(stroke
				(width 0.1)
				(type default)
			)
			(layer "F.Fab")
		)
		(fp_line
			(start -0.12065 0.3048)
			(end -0.67945 0.3048)
			(stroke
				(width 0.1)
				(type default)
			)
			(layer "F.Fab")
		)
		(fp_line
			(start 0.120396 0.2794)
			(end -0.12065 0.2794)
			(stroke
				(width 0.1)
				(type default)
			)
			(layer "F.Fab")
		)
		(fp_line
			(start 0.120396 0.3048)
			(end 0.120396 0.2794)
			(stroke
				(width 0.1)
				(type default)
			)
			(layer "F.Fab")
		)
		(fp_line
			(start 0.12065 -0.3048)
			(end 0.67945 -0.3048)
			(stroke
				(width 0.1)
				(type default)
			)
			(layer "F.Fab")
		)
		(fp_line
			(start 0.12065 -0.2794)
			(end 0.12065 -0.3048)
			(stroke
				(width 0.1)
				(type default)
			)
			(layer "F.Fab")
		)
		(fp_line
			(start 0.67945 -0.3048)
			(end 0.67945 0.3048)
			(stroke
				(width 0.1)
				(type default)
			)
			(layer "F.Fab")
		)
		(fp_line
			(start 0.67945 0.3048)
			(end 0.120396 0.3048)
			(stroke
				(width 0.1)
				(type default)
			)
			(layer "F.Fab")
		)
		(pad "1" smd circle
			(at -0.40005 0)
			(size 0 0)
			(layers "F.Cu" "F.Mask" "F.Paste")
			(net "PVCCFA_EHV_FIVRA_CPU0_BTSEN")
		)
		(pad "2" smd circle
			(at 0.40005 0)
			(size 0 0)
			(layers "F.Cu" "F.Mask" "F.Paste")
			(net "GND")
		)
	)
	(footprint ""
		(layer "F.Cu")
		(at 357.487982 -386.41909 180)
		(property "Reference" "R4159"
			(at 0 0 180)
			(layer "F.SilkS")
			(hide yes)
			(effects
				(font
					(size 1.27 1.27)
				)
			)
		)
		(property "Value" ""
			(at 0 0 180)
			(layer "F.Fab")
			(effects
				(font
					(size 1.27 1.27)
				)
			)
		)
		(duplicate_pad_numbers_are_jumpers no)
		(fp_line
			(start 0.7874 0.4064)
			(end -0.7874 0.4064)
			(stroke
				(width 0.1524)
				(type default)
			)
			(layer "F.SilkS")
		)
		(fp_line
			(start 0.7874 -0.4064)
			(end 0.7874 0.4064)
			(stroke
				(width 0.1524)
				(type default)
			)
			(layer "F.SilkS")
		)
		(fp_line
			(start -0.7874 0.4064)
			(end -0.7874 -0.4064)
			(stroke
				(width 0.1524)
				(type default)
			)
			(layer "F.SilkS")
		)
		(fp_line
			(start -0.7874 -0.4064)
			(end 0.7874 -0.4064)
			(stroke
				(width 0.1524)
				(type default)
			)
			(layer "F.SilkS")
		)
		(fp_line
			(start 0.67945 0.3048)
			(end 0.120396 0.3048)
			(stroke
				(width 0.1)
				(type default)
			)
			(layer "F.Fab")
		)
		(fp_line
			(start 0.67945 -0.3048)
			(end 0.67945 0.3048)
			(stroke
				(width 0.1)
				(type default)
			)
			(layer "F.Fab")
		)
		(fp_line
			(start 0.12065 -0.2794)
			(end 0.12065 -0.3048)
			(stroke
				(width 0.1)
				(type default)
			)
			(layer "F.Fab")
		)
		(fp_line
			(start 0.12065 -0.3048)
			(end 0.67945 -0.3048)
			(stroke
				(width 0.1)
				(type default)
			)
			(layer "F.Fab")
		)
		(fp_line
			(start 0.120396 0.3048)
			(end 0.120396 0.2794)
			(stroke
				(width 0.1)
				(type default)
			)
			(layer "F.Fab")
		)
		(fp_line
			(start 0.120396 0.2794)
			(end -0.12065 0.2794)
			(stroke
				(width 0.1)
				(type default)
			)
			(layer "F.Fab")
		)
		(fp_line
			(start -0.12065 0.3048)
			(end -0.67945 0.3048)
			(stroke
				(width 0.1)
				(type default)
			)
			(layer "F.Fab")
		)
		(fp_line
			(start -0.12065 0.2794)
			(end -0.12065 0.3048)
			(stroke
				(width 0.1)
				(type default)
			)
			(layer "F.Fab")
		)
		(fp_line
			(start -0.12065 -0.2794)
			(end 0.12065 -0.2794)
			(stroke
				(width 0.1)
				(type default)
			)
			(layer "F.Fab")
		)
		(fp_line
			(start -0.12065 -0.305054)
			(end -0.12065 -0.2794)
			(stroke
				(width 0.1)
				(type default)
			)
			(layer "F.Fab")
		)
		(fp_line
			(start -0.67945 0.3048)
			(end -0.67945 -0.305054)
			(stroke
				(width 0.1)
				(type default)
			)
			(layer "F.Fab")
		)
		(fp_line
			(start -0.67945 -0.305054)
			(end -0.12065 -0.305054)
			(stroke
				(width 0.1)
				(type default)
			)
			(layer "F.Fab")
		)
		(pad "1" smd circle
			(at -0.40005 0 180)
			(size 0 0)
			(layers "F.Cu" "F.Mask" "F.Paste")
			(net "GPU_3V3IO_RSVD1")
		)
		(pad "2" smd circle
			(at 0.40005 0 180)
			(size 0 0)
			(layers "F.Cu" "F.Mask" "F.Paste")
			(net "GND")
		)
	)
)
